G04 ================== begin FILE IDENTIFICATION RECORD ==================*
G04 Layout Name:  D:/<user>/Wistron_project/16342-2/gbr/16342-2.brd*
G04 Film Name:    DP_REF_L3*
G04 File Format:  Gerber RS274X*
G04 File Origin:  Cadence Allegro 16.5-S056*
G04 Origin Date:  Mon Aug 07 11:25:03 2017*
G04 *
G04 Layer:  BOARD GEOMETRY/DP_REF_L3_TBL*
G04 Layer:  BOARD GEOMETRY/DP_REF_L3_L3*
G04 Layer:  BOARD GEOMETRY/PANEL_OUTLINE*
G04 *
G04 Offset:    (0.00 0.00)*
G04 Mirror:    No*
G04 Mode:      Positive*
G04 Rotation:  0*
G04 FullContactRelief:  No*
G04 UndefLineWidth:     6.00*
G04 ================== end FILE IDENTIFICATION RECORD ====================*
%FSLAX35Y35*MOIN*%
%IR0*IPPOS*OFA0.00000B0.00000*MIA0B0*SFA1.00000B1.00000*%
%ADD10C,.02*%
%ADD11C,.004*%
%ADD12C,.006*%
%ADD13C,.0055*%
G75*
%LPD*%
G75*
G54D10*
G01X975497Y625480D02*
X1762997D01*
G01X975497Y729430D02*
Y625480D01*
G01Y694780D02*
X1762997D01*
G01X975497Y660130D02*
X1762997D01*
G01X975497Y729430D02*
X1762997D01*
G01X1150497D02*
Y625480D01*
G01X1447997Y729430D02*
Y625480D01*
G01X1552997Y729430D02*
Y625480D01*
G01X1762997Y729430D02*
Y625480D01*
G54D11*
G01X80736Y562222D02*
Y569527D01*
G01X81936D02*
Y562222D01*
G01X78018D02*
G03X80736I1359J0D01*
G01X81936D02*
G02X76818I-2559J0D01*
G01X78018Y572748D02*
Y562222D01*
G01X76818D02*
Y572749D01*
G01Y562222D02*
Y572749D01*
G01X78018Y572748D02*
Y562222D01*
G01X81936D02*
G02X76818I-2559J0D01*
G01X78018D02*
G03X80736I1359J0D01*
G01X81936Y569527D02*
Y562222D01*
G01X80736D02*
Y569527D01*
G01X88507Y557140D02*
X87725D01*
G01X88009Y555940D02*
X87725D01*
G01X89357Y556290D02*
X88507Y557140D01*
G01X88859Y555090D02*
X88009Y555940D01*
G01X90769Y556290D02*
X89357D01*
G01X90770Y555090D02*
X88859D01*
G01X91325Y556521D02*
G02X90769Y556290I-557J556D01*
G01X92174Y555672D02*
G02X90770Y555090I-1405J1405D01*
G01X92756Y557077D02*
G02X92174Y555672I-1987J0D01*
G01X91556Y557077D02*
G02X91325Y556521I-787J1D01*
G01X92174Y555672D02*
G02X90770Y555090I-1405J1405D01*
G01X92756Y557077D02*
G02X92174Y555672I-1987J0D01*
G01X91556Y557612D02*
Y557077D01*
G01X92756Y557612D02*
Y557077D01*
G01X92146Y559186D02*
G03X91556Y557612I1800J-1572D01*
G01X93032Y558375D02*
G03X92756Y557612I914J-762D01*
G01X94044Y559994D02*
G03X92146Y559186I-1J-2631D01*
G01X94044Y558794D02*
G03X93032Y558375I0J-1431D01*
G01X98267Y559994D02*
X94044D01*
G01X98267Y558794D02*
X94044D01*
G01X98832Y560229D02*
G02X98267Y559994I-566J564D01*
G01X99681Y559380D02*
G02X98267Y558794I-1414J1413D01*
G01X106671Y568068D02*
X98832Y560229D01*
G01X107520Y567219D02*
X99681Y559380D01*
G01X88009Y555940D02*
X87725D01*
G01X88507Y557140D02*
X87725D01*
G01X88859Y555090D02*
X88009Y555940D01*
G01X89357Y556290D02*
X88507Y557140D01*
G01X90770Y555090D02*
X88859D01*
G01X90769Y556290D02*
X89357D01*
G01X92174Y555672D02*
G02X90770Y555090I-1405J1405D01*
G01X91325Y556521D02*
G02X90769Y556290I-557J556D01*
G01X91556Y557077D02*
G02X91325Y556521I-787J1D01*
G01X92756Y557077D02*
G02X92174Y555672I-1987J0D01*
G01X91325Y556521D02*
G02X90769Y556290I-557J556D01*
G01X91556Y557077D02*
G02X91325Y556521I-787J1D01*
G01X92756Y557612D02*
Y557077D01*
G01X91556Y557612D02*
Y557077D01*
G01X93032Y558375D02*
G03X92756Y557612I914J-762D01*
G01X92146Y559186D02*
G03X91556Y557612I1800J-1572D01*
G01X94044Y558794D02*
G03X93032Y558375I0J-1431D01*
G01X94044Y559994D02*
G03X92146Y559186I-1J-2631D01*
G01X98267Y558794D02*
X94044D01*
G01X98267Y559994D02*
X94044D01*
G01X99681Y559380D02*
G02X98267Y558794I-1414J1413D01*
G01X98832Y560229D02*
G02X98267Y559994I-566J564D01*
G01X107520Y567219D02*
X99681Y559380D01*
G01X106671Y568068D02*
X98832Y560229D01*
G01X93871Y584142D02*
X88410D01*
G01Y585342D02*
X93871D01*
G01Y590601D02*
G02Y584142I0J-3229D01*
G01Y585342D02*
G03Y589401I0J2030D01*
G01X84327Y590601D02*
X93871D01*
G01Y589401D02*
X84327D01*
G01Y593986D02*
G03Y590601I0J-1692D01*
G01Y589401D02*
G02Y595186I0J2893D01*
G01X98948Y593986D02*
X84327D01*
G01Y595186D02*
X98948D01*
G01X100393Y593116D02*
G03X98948Y593986I-1445J-765D01*
G01Y595186D02*
G02X101455Y593678I1J-2836D01*
G01X103183Y590899D02*
G02X100393Y593116I0J2864D01*
G01X101562Y593387D02*
G03X103183Y592099I1621J376D01*
G01X105496Y592484D02*
G02X103183Y590899I-2313J895D01*
G01Y592099D02*
G03X104376Y592917I0J1279D01*
G01X108642Y592641D02*
G03X105496Y592484I-1535J-836D01*
G01X104390Y592950D02*
G02X109696Y593215I2717J-1145D01*
G01X111186Y590932D02*
G02X108642Y592641I0J2748D01*
G01X111186Y592132D02*
G03X112628Y593237I0J1493D01*
G01X109769Y593056D02*
G03X111186Y592132I1417J625D01*
G01X113788Y592925D02*
G02X111186Y590932I-2602J702D01*
G01Y592132D02*
G03X112628Y593237I0J1493D01*
G01X109769Y593056D02*
G03X111186Y592132I1417J625D01*
G01X115214Y593986D02*
G03X113788Y592925I-41J-1433D01*
G01X112629Y593237D02*
G02X115248Y595186I2544J-684D01*
G01X117291Y593986D02*
X115214D01*
G01X115248Y595186D02*
X117291D01*
G01X119899Y595053D02*
G02X117291Y593986I-2608J2654D01*
G01Y595186D02*
G03X119054Y595906I-1J2520D01*
G01X121138Y596292D02*
X119899Y595053D01*
G01X119054Y595906D02*
X120289Y597141D01*
G01X124128Y597530D02*
G03X121138Y596292I0J-4230D01*
G01X120289Y597141D02*
G02X124127Y598730I3838J-3841D01*
G01X138717Y597530D02*
X124128D01*
G01X124127Y598730D02*
X138717D01*
G01X140090Y596157D02*
G03X138717Y597530I-1373J0D01*
G01Y598730D02*
G02X141290Y596157I0J-2573D01*
G01X140090Y591123D02*
Y596157D01*
G01X142800Y588413D02*
G02X140090Y591123I0J2710D01*
G01X142800Y588413D02*
G02X140090Y591123I0J2710D01*
G01D02*
Y596157D01*
G01X138717Y598730D02*
G02X141290Y596157I0J-2573D01*
G01X140090D02*
G03X138717Y597530I-1373J0D01*
G01X124127Y598730D02*
X138717D01*
G01Y597530D02*
X124128D01*
G01X120289Y597141D02*
G02X124127Y598730I3838J-3841D01*
G01X124128Y597530D02*
G03X121138Y596292I0J-4230D01*
G01X119054Y595906D02*
X120289Y597141D01*
G01X121138Y596292D02*
X119899Y595053D01*
G01X117291Y595186D02*
G03X119054Y595906I-1J2520D01*
G01X119899Y595053D02*
G02X117291Y593986I-2608J2654D01*
G01X115248Y595186D02*
X117291D01*
G01Y593986D02*
X115214D01*
G01X112629Y593237D02*
G02X115248Y595186I2544J-684D01*
G01X115214Y593986D02*
G03X113788Y592925I-41J-1433D01*
G01X111186Y592132D02*
G03X112628Y593237I0J1493D01*
G01X111186Y590932D02*
G02X108642Y592641I0J2748D01*
G01X113788Y592925D02*
G02X111186Y590932I-2602J702D01*
G01X109769Y593056D02*
G03X111186Y592132I1417J625D01*
G01Y590932D02*
G02X108642Y592641I0J2748D01*
G01X113788Y592925D02*
G02X111186Y590932I-2602J702D01*
G01X104390Y592950D02*
G02X109696Y593215I2717J-1145D01*
G01X108642Y592641D02*
G03X105496Y592484I-1535J-836D01*
G01X103183Y592099D02*
G03X104376Y592917I0J1279D01*
G01X105496Y592484D02*
G02X103183Y590899I-2313J895D01*
G01X101562Y593387D02*
G03X103183Y592099I1621J376D01*
G01Y590899D02*
G02X100393Y593116I0J2864D01*
G01X98948Y595186D02*
G02X101455Y593678I1J-2836D01*
G01X100393Y593116D02*
G03X98948Y593986I-1445J-765D01*
G01X84327Y595186D02*
X98948D01*
G01Y593986D02*
X84327D01*
G01Y589401D02*
G02Y595186I0J2893D01*
G01Y593986D02*
G03Y590601I0J-1692D01*
G01X93871Y589401D02*
X84327D01*
G01Y590601D02*
X93871D01*
G01Y585342D02*
G03Y589401I0J2030D01*
G01Y590601D02*
G02Y584142I0J-3229D01*
G01X88410Y585342D02*
X93871D01*
G01Y584142D02*
X88410D01*
G01X138204Y578206D02*
X146542D01*
G01Y577006D02*
X138204D01*
G01X135022Y579524D02*
G03X138204Y578206I3182J3182D01*
G01Y577006D02*
G02X134173Y578675I-1J5700D01*
G01X133789Y580757D02*
X135022Y579524D01*
G01X134173Y578675D02*
X132940Y579908D01*
G01X130906Y581950D02*
G02X133789Y580757I2J-4075D01*
G01X132940Y579908D02*
G03X130906Y580750I-2033J-2033D01*
G01X106693Y581950D02*
X130906D01*
G01Y580750D02*
X106694D01*
G01X104312Y580964D02*
G02X106693Y581950I2381J-2382D01*
G01X106694Y580750D02*
G03X105161Y580115I0J-2168D01*
G01X95386Y572039D02*
X104312Y580964D01*
G01X97193Y572147D02*
X96235Y571190D01*
G01X105161Y580115D02*
X97193Y572147D01*
G01X93775Y571371D02*
G03X95386Y572039I-1J2279D01*
G01X96235Y571190D02*
G02X93776Y570171I-2460J2460D01*
G01X82580Y571371D02*
X93775D01*
G01X83141Y570171D02*
X82580D01*
G01X88701D02*
X87501D01*
G01X93776D02*
X93061D01*
G01X80736Y569527D02*
G02X82580Y571371I1844J0D01*
G01Y570171D02*
G03X81936Y569527I0J-644D01*
G01X77286Y574518D02*
G02X78018Y572748I-1770J-1768D01*
G01X76437Y573668D02*
G03X75518Y574048I-919J-921D01*
G01X76818Y572749D02*
G03X76437Y573669I-1302J0D01*
G01X75518Y575248D02*
G02X77286Y574518I2J-2502D01*
G01X76437Y573668D02*
G03X75518Y574048I-919J-921D01*
G01X76818Y572749D02*
G03X76437Y573669I-1302J0D01*
G01X74737Y575248D02*
X75518D01*
G01Y574048D02*
X74737D01*
G01X72555Y574345D02*
G02X74737Y575248I2181J-2183D01*
G01Y574048D02*
G03X73404Y573496I0J-1886D01*
G01X71554Y571996D02*
G02X72506Y574296I3252J1D01*
G01X73355Y573447D02*
G03X72754Y571996I1451J-1451D01*
G01X71554Y568898D02*
Y571996D01*
G01X72754D02*
Y568569D01*
G01Y571996D02*
Y568569D01*
G01X71554Y568898D02*
Y571996D01*
G01X73355Y573447D02*
G03X72754Y571996I1451J-1451D01*
G01X71554D02*
G02X72506Y574296I3252J1D01*
G01X74737Y574048D02*
G03X73404Y573496I0J-1886D01*
G01X72555Y574345D02*
G02X74737Y575248I2181J-2183D01*
G01X75518Y574048D02*
X74737D01*
G01Y575248D02*
X75518D01*
G01X76437Y573668D02*
G03X75518Y574048I-919J-921D01*
G01X77286Y574518D02*
G02X78018Y572748I-1770J-1768D01*
G01X75518Y575248D02*
G02X77286Y574518I2J-2502D01*
G01X76818Y572749D02*
G03X76437Y573669I-1302J0D01*
G01X77286Y574518D02*
G02X78018Y572748I-1770J-1768D01*
G01X75518Y575248D02*
G02X77286Y574518I2J-2502D01*
G01X82580Y570171D02*
G03X81936Y569527I0J-644D01*
G01X80736D02*
G02X82580Y571371I1844J0D01*
G01X83141Y570171D02*
X82580D01*
G01Y571371D02*
X93775D01*
G01X88701Y570171D02*
X87501D01*
G01X82580Y571371D02*
X93775D01*
G01X93776Y570171D02*
X93061D01*
G01X82580Y571371D02*
X93775D01*
G01X96235Y571190D02*
G02X93776Y570171I-2460J2460D01*
G01X93775Y571371D02*
G03X95386Y572039I-1J2279D01*
G01X97193Y572147D02*
X96235Y571190D01*
G01X95386Y572039D02*
X104312Y580964D01*
G01X105161Y580115D02*
X97193Y572147D01*
G01X95386Y572039D02*
X104312Y580964D01*
G01X106694Y580750D02*
G03X105161Y580115I0J-2168D01*
G01X104312Y580964D02*
G02X106693Y581950I2381J-2382D01*
G01X130906Y580750D02*
X106694D01*
G01X106693Y581950D02*
X130906D01*
G01X132940Y579908D02*
G03X130906Y580750I-2033J-2033D01*
G01Y581950D02*
G02X133789Y580757I2J-4075D01*
G01X134173Y578675D02*
X132940Y579908D01*
G01X133789Y580757D02*
X135022Y579524D01*
G01X138204Y577006D02*
G02X134173Y578675I-1J5700D01*
G01X135022Y579524D02*
G03X138204Y578206I3182J3182D01*
G01X146542Y577006D02*
X138204D01*
G01Y578206D02*
X146542D01*
G01X108934Y569005D02*
G03X106671Y568068I-1J-3199D01*
G01X108934Y567805D02*
G03X107520Y567219I0J-1999D01*
G01X112619Y569005D02*
X108934D01*
G01X112619Y567805D02*
X108934D01*
G01X113184Y569240D02*
G02X112619Y569005I-566J564D01*
G01X114033Y568391D02*
G02X112619Y567805I-1414J1413D01*
G01X114807Y570863D02*
X113184Y569240D01*
G01X115656Y570014D02*
X114033Y568391D01*
G01X117070Y571800D02*
G03X114807Y570863I-1J-3199D01*
G01X117070Y570600D02*
G03X115656Y570014I0J-1999D01*
G01X120283Y571800D02*
X117070D01*
G01X120259Y570600D02*
X117070D01*
G01X123000Y569027D02*
G03X120283Y571800I-2774J0D01*
G01X121800Y569027D02*
G03X120259Y570600I-1573J0D01*
G01X123000Y568555D02*
Y569027D01*
G01X121800Y568555D02*
Y569027D01*
G01X124344Y567211D02*
G02X123000Y568555I0J1344D01*
G01X124344Y566011D02*
G02X121800Y568555I0J2544D01*
G01X127267Y567211D02*
X124344D01*
G01X127267Y566011D02*
X124344D01*
G01X127777Y567721D02*
G02X127267Y567211I-510J0D01*
G01X128977Y567721D02*
G02X127267Y566011I-1710J0D01*
G01X127777Y568126D02*
Y567721D01*
G01X128977Y568006D02*
Y567721D01*
G01X108934Y567805D02*
G03X107520Y567219I0J-1999D01*
G01X108934Y569005D02*
G03X106671Y568068I-1J-3199D01*
G01X112619Y567805D02*
X108934D01*
G01X112619Y569005D02*
X108934D01*
G01X114033Y568391D02*
G02X112619Y567805I-1414J1413D01*
G01X113184Y569240D02*
G02X112619Y569005I-566J564D01*
G01X115656Y570014D02*
X114033Y568391D01*
G01X114807Y570863D02*
X113184Y569240D01*
G01X117070Y570600D02*
G03X115656Y570014I0J-1999D01*
G01X117070Y571800D02*
G03X114807Y570863I-1J-3199D01*
G01X120259Y570600D02*
X117070D01*
G01X120283Y571800D02*
X117070D01*
G01X121800Y569027D02*
G03X120259Y570600I-1573J0D01*
G01X123000Y569027D02*
G03X120283Y571800I-2774J0D01*
G01X121800Y568555D02*
Y569027D01*
G01X123000Y568555D02*
Y569027D01*
G01X124344Y566011D02*
G02X121800Y568555I0J2544D01*
G01X124344Y567211D02*
G02X123000Y568555I0J1344D01*
G01X127267Y566011D02*
X124344D01*
G01X127267Y567211D02*
X124344D01*
G01X128977Y567721D02*
G02X127267Y566011I-1710J0D01*
G01X127777Y567721D02*
G02X127267Y567211I-510J0D01*
G01X128977Y568006D02*
Y567721D01*
G01X127777Y568126D02*
Y567721D01*
G01X141290Y596157D02*
Y591123D01*
G01D02*
G03X142800Y589613I1510J0D01*
G01X143470Y588413D02*
X142800D01*
G01Y589613D02*
X143469D01*
G01X142800D02*
X143469D01*
G01X143470Y588413D02*
X142800D01*
G01X141290Y591123D02*
G03X142800Y589613I1510J0D01*
G01X141290Y596157D02*
Y591123D01*
G54D12*
G01X6250Y-32800D02*
Y-50300D01*
G01X1228Y-32800D02*
X11272D01*
G01X20038Y-50300D02*
Y-32800D01*
G01Y-41258D02*
X21130Y-39800D01*
X22222Y-38925D01*
X23968Y-38634D01*
X25278Y-38925D01*
X26807Y-40092D01*
X27462Y-41842D01*
Y-50300D01*
G01X41250Y-38634D02*
Y-50300D01*
G01Y-33967D02*
X40813Y-33675D01*
Y-33092D01*
X41250Y-32800D01*
X41687Y-33092D01*
Y-33675D01*
X41250Y-33967D01*
G01X55475Y-48259D02*
X56567Y-49425D01*
X58095Y-50300D01*
X59405D01*
X60715Y-49717D01*
X61588Y-48842D01*
X62025Y-47676D01*
X61807Y-45925D01*
X60933Y-45050D01*
X57003Y-43300D01*
X56130Y-41258D01*
X56567Y-39800D01*
X57440Y-38925D01*
X58750Y-38634D01*
X60060Y-38925D01*
X61370Y-39800D01*
G01X90693Y-54675D02*
X92222Y-55842D01*
X93968Y-56133D01*
X95496Y-55842D01*
X96807Y-54384D01*
X97680Y-52342D01*
Y-38634D01*
G01Y-40967D02*
X96807Y-39800D01*
X95496Y-38925D01*
X93968Y-38634D01*
X92222Y-39217D01*
X91130Y-40383D01*
X90256Y-42425D01*
X89820Y-44467D01*
X90038Y-46217D01*
X90912Y-48259D01*
X92222Y-49717D01*
X93968Y-50300D01*
X95278Y-50008D01*
X96807Y-48842D01*
X97680Y-47676D01*
G01X107975Y-42425D02*
X114962D01*
X114307Y-40383D01*
X113215Y-39217D01*
X111687Y-38634D01*
X110158Y-38925D01*
X108848Y-39800D01*
X107975Y-41842D01*
X107538Y-43592D01*
Y-45342D01*
X107975Y-47092D01*
X109067Y-48842D01*
X110377Y-50008D01*
X111905Y-50300D01*
X113433Y-49717D01*
X114962Y-47967D01*
G01X125693Y-50300D02*
Y-38634D01*
G01Y-40967D02*
X126785Y-39800D01*
X127877Y-38925D01*
X129405Y-38634D01*
X130496Y-38925D01*
X131807Y-39800D01*
G01X142320Y-50300D02*
Y-32800D01*
G01Y-41550D02*
X143412Y-39800D01*
X144722Y-38925D01*
X146032Y-38634D01*
X147996Y-39217D01*
X149307Y-40383D01*
X150180Y-42425D01*
Y-44758D01*
X149743Y-47092D01*
X148870Y-48842D01*
X147342Y-50008D01*
X146032Y-50300D01*
X144722Y-50008D01*
X143412Y-49134D01*
X142320Y-47676D01*
G01X160475Y-42425D02*
X167462D01*
X166807Y-40383D01*
X165715Y-39217D01*
X164187Y-38634D01*
X162658Y-38925D01*
X161348Y-39800D01*
X160475Y-41842D01*
X160038Y-43592D01*
Y-45342D01*
X160475Y-47092D01*
X161567Y-48842D01*
X162877Y-50008D01*
X164405Y-50300D01*
X165933Y-49717D01*
X167462Y-47967D01*
G01X178193Y-50300D02*
Y-38634D01*
G01Y-40967D02*
X179285Y-39800D01*
X180377Y-38925D01*
X181905Y-38634D01*
X182996Y-38925D01*
X184307Y-39800D01*
G01X216250Y-38634D02*
Y-50300D01*
G01Y-33967D02*
X215813Y-33675D01*
Y-33092D01*
X216250Y-32800D01*
X216687Y-33092D01*
Y-33675D01*
X216250Y-33967D01*
G01X230475Y-48259D02*
X231567Y-49425D01*
X233095Y-50300D01*
X234405D01*
X235715Y-49717D01*
X236588Y-48842D01*
X237025Y-47676D01*
X236807Y-45925D01*
X235933Y-45050D01*
X232003Y-43300D01*
X231130Y-41258D01*
X231567Y-39800D01*
X232440Y-38925D01*
X233750Y-38634D01*
X235060Y-38925D01*
X236370Y-39800D01*
G01X265256Y-54675D02*
X266785Y-55842D01*
X268095Y-56133D01*
X269842Y-55550D01*
X271152Y-54092D01*
X271807Y-51466D01*
Y-38634D01*
G01Y-33967D02*
X271370Y-33675D01*
Y-33092D01*
X271807Y-32800D01*
X272243Y-33092D01*
Y-33675D01*
X271807Y-33967D01*
G01X282538Y-38634D02*
Y-46800D01*
X283412Y-48842D01*
X284722Y-50008D01*
X286250Y-50300D01*
X287778Y-50008D01*
X289088Y-48842D01*
X289962Y-46800D01*
G01Y-50300D02*
Y-38634D01*
G01X300475Y-48259D02*
X301567Y-49425D01*
X303095Y-50300D01*
X304405D01*
X305715Y-49717D01*
X306588Y-48842D01*
X307025Y-47676D01*
X306807Y-45925D01*
X305933Y-45050D01*
X302003Y-43300D01*
X301130Y-41258D01*
X301567Y-39800D01*
X302440Y-38925D01*
X303750Y-38634D01*
X305060Y-38925D01*
X306370Y-39800D01*
G01X321250Y-32800D02*
Y-50300D01*
G01X318193Y-38634D02*
X324307D01*
G01X354940Y-50300D02*
Y-35425D01*
X355377Y-33967D01*
X356250Y-33092D01*
X357560Y-32800D01*
X358870Y-33383D01*
X359525Y-34842D01*
G01X356905Y-39800D02*
X352538D01*
G01X373750Y-50300D02*
X372440Y-50008D01*
X371130Y-48842D01*
X370256Y-46800D01*
X369820Y-44467D01*
X370256Y-42133D01*
X371130Y-40092D01*
X372440Y-38925D01*
X373750Y-38634D01*
X375060Y-38925D01*
X376370Y-40092D01*
X377243Y-42133D01*
X377462Y-44467D01*
X377243Y-46800D01*
X376370Y-48842D01*
X375060Y-50008D01*
X373750Y-50300D01*
G01X388193D02*
Y-38634D01*
G01Y-40967D02*
X389285Y-39800D01*
X390377Y-38925D01*
X391905Y-38634D01*
X392996Y-38925D01*
X394307Y-39800D01*
G01X421665Y-55550D02*
X422975Y-56133D01*
X424722Y-55550D01*
X425813Y-54384D01*
X426687Y-52925D01*
X427996Y-48259D01*
X430835Y-38634D01*
G01X423848D02*
X427996Y-48259D01*
G01X443750Y-50300D02*
X442440Y-50008D01*
X441130Y-48842D01*
X440256Y-46800D01*
X439820Y-44467D01*
X440256Y-42133D01*
X441130Y-40092D01*
X442440Y-38925D01*
X443750Y-38634D01*
X445060Y-38925D01*
X446370Y-40092D01*
X447243Y-42133D01*
X447462Y-44467D01*
X447243Y-46800D01*
X446370Y-48842D01*
X445060Y-50008D01*
X443750Y-50300D01*
G01X457538Y-38634D02*
Y-46800D01*
X458412Y-48842D01*
X459722Y-50008D01*
X461250Y-50300D01*
X462778Y-50008D01*
X464088Y-48842D01*
X464962Y-46800D01*
G01Y-50300D02*
Y-38634D01*
G01X475693Y-50300D02*
Y-38634D01*
G01Y-40967D02*
X476785Y-39800D01*
X477877Y-38925D01*
X479405Y-38634D01*
X480496Y-38925D01*
X481807Y-39800D01*
G01X510693Y-50300D02*
Y-38634D01*
G01Y-40967D02*
X511785Y-39800D01*
X512877Y-38925D01*
X514405Y-38634D01*
X515496Y-38925D01*
X516807Y-39800D01*
G01X527975Y-42425D02*
X534962D01*
X534307Y-40383D01*
X533215Y-39217D01*
X531687Y-38634D01*
X530158Y-38925D01*
X528848Y-39800D01*
X527975Y-41842D01*
X527538Y-43592D01*
Y-45342D01*
X527975Y-47092D01*
X529067Y-48842D01*
X530377Y-50008D01*
X531905Y-50300D01*
X533433Y-49717D01*
X534962Y-47967D01*
G01X547440Y-50300D02*
Y-35425D01*
X547877Y-33967D01*
X548750Y-33092D01*
X550060Y-32800D01*
X551370Y-33383D01*
X552025Y-34842D01*
G01X549405Y-39800D02*
X545038D01*
G01X562975Y-42425D02*
X569962D01*
X569307Y-40383D01*
X568215Y-39217D01*
X566687Y-38634D01*
X565158Y-38925D01*
X563848Y-39800D01*
X562975Y-41842D01*
X562538Y-43592D01*
Y-45342D01*
X562975Y-47092D01*
X564067Y-48842D01*
X565377Y-50008D01*
X566905Y-50300D01*
X568433Y-49717D01*
X569962Y-47967D01*
G01X580693Y-50300D02*
Y-38634D01*
G01Y-40967D02*
X581785Y-39800D01*
X582877Y-38925D01*
X584405Y-38634D01*
X585496Y-38925D01*
X586807Y-39800D01*
G01X597975Y-42425D02*
X604962D01*
X604307Y-40383D01*
X603215Y-39217D01*
X601687Y-38634D01*
X600158Y-38925D01*
X598848Y-39800D01*
X597975Y-41842D01*
X597538Y-43592D01*
Y-45342D01*
X597975Y-47092D01*
X599067Y-48842D01*
X600377Y-50008D01*
X601905Y-50300D01*
X603433Y-49717D01*
X604962Y-47967D01*
G01X615038Y-50300D02*
Y-38634D01*
G01Y-41550D02*
X615912Y-40092D01*
X617222Y-38925D01*
X618968Y-38634D01*
X620496Y-38925D01*
X621807Y-40092D01*
X622462Y-42133D01*
Y-50300D01*
G01X639743Y-40092D02*
X638215Y-38925D01*
X636905Y-38634D01*
X635158Y-39217D01*
X633848Y-40383D01*
X632975Y-42425D01*
X632756Y-44467D01*
X632975Y-46509D01*
X633848Y-48259D01*
X635158Y-49717D01*
X636905Y-50300D01*
X638433Y-49717D01*
X639743Y-48550D01*
G01X650475Y-42425D02*
X657462D01*
X656807Y-40383D01*
X655715Y-39217D01*
X654187Y-38634D01*
X652658Y-38925D01*
X651348Y-39800D01*
X650475Y-41842D01*
X650038Y-43592D01*
Y-45342D01*
X650475Y-47092D01*
X651567Y-48842D01*
X652877Y-50008D01*
X654405Y-50300D01*
X655933Y-49717D01*
X657462Y-47967D01*
G01X688750Y-32800D02*
Y-50300D01*
G01X685693Y-38634D02*
X691807D01*
G01X706250Y-50300D02*
X704940Y-50008D01*
X703630Y-48842D01*
X702756Y-46800D01*
X702320Y-44467D01*
X702756Y-42133D01*
X703630Y-40092D01*
X704940Y-38925D01*
X706250Y-38634D01*
X707560Y-38925D01*
X708870Y-40092D01*
X709743Y-42133D01*
X709962Y-44467D01*
X709743Y-46800D01*
X708870Y-48842D01*
X707560Y-50008D01*
X706250Y-50300D01*
G01X739940D02*
Y-35425D01*
X740377Y-33967D01*
X741250Y-33092D01*
X742560Y-32800D01*
X743870Y-33383D01*
X744525Y-34842D01*
G01X741905Y-39800D02*
X737538D01*
G01X758750Y-38634D02*
Y-50300D01*
G01Y-33967D02*
X758313Y-33675D01*
Y-33092D01*
X758750Y-32800D01*
X759187Y-33092D01*
Y-33675D01*
X758750Y-33967D01*
G01X772538Y-50300D02*
Y-38634D01*
G01Y-41550D02*
X773412Y-40092D01*
X774722Y-38925D01*
X776468Y-38634D01*
X777996Y-38925D01*
X779307Y-40092D01*
X779962Y-42133D01*
Y-50300D01*
G01X797680Y-32800D02*
Y-50300D01*
G01Y-47676D02*
X796807Y-49134D01*
X795496Y-50008D01*
X793968Y-50300D01*
X792222Y-49717D01*
X790912Y-48259D01*
X790038Y-46509D01*
X789820Y-44467D01*
X790038Y-42425D01*
X790912Y-40675D01*
X792222Y-39217D01*
X793968Y-38634D01*
X795496Y-38925D01*
X796588Y-39509D01*
X797680Y-40675D01*
G01X828750Y-32800D02*
Y-50300D01*
G01X825693Y-38634D02*
X831807D01*
G01X842538Y-50300D02*
Y-32800D01*
G01Y-41258D02*
X843630Y-39800D01*
X844722Y-38925D01*
X846468Y-38634D01*
X847778Y-38925D01*
X849307Y-40092D01*
X849962Y-41842D01*
Y-50300D01*
G01X860475Y-42425D02*
X867462D01*
X866807Y-40383D01*
X865715Y-39217D01*
X864187Y-38634D01*
X862658Y-38925D01*
X861348Y-39800D01*
X860475Y-41842D01*
X860038Y-43592D01*
Y-45342D01*
X860475Y-47092D01*
X861567Y-48842D01*
X862877Y-50008D01*
X864405Y-50300D01*
X865933Y-49717D01*
X867462Y-47967D01*
G01X893947Y-50300D02*
Y-32800D01*
X898313D01*
X900060Y-33675D01*
X901370Y-34842D01*
X902462Y-36591D01*
X903335Y-38634D01*
X903553Y-41550D01*
X903335Y-44467D01*
X902462Y-46509D01*
X901370Y-48259D01*
X900060Y-49425D01*
X898313Y-50300D01*
X893947D01*
G01X911883D02*
Y-32800D01*
X917123D01*
X918870Y-33675D01*
X920180Y-35717D01*
X920617Y-38050D01*
X920180Y-40383D01*
X919088Y-42133D01*
X917123Y-43009D01*
X911883D01*
G01X951250Y-38634D02*
Y-50300D01*
G01Y-33967D02*
X950813Y-33675D01*
Y-33092D01*
X951250Y-32800D01*
X951687Y-33092D01*
Y-33675D01*
X951250Y-33967D01*
G01X962200Y-50300D02*
Y-38634D01*
G01Y-41842D02*
X962855Y-40383D01*
X963947Y-39217D01*
X965475Y-38634D01*
X967003Y-39217D01*
X968095Y-40383D01*
X968750Y-41842D01*
Y-50300D01*
G01Y-41842D02*
X969405Y-40383D01*
X970496Y-39217D01*
X972025Y-38634D01*
X973553Y-39217D01*
X974645Y-40383D01*
X975300Y-42133D01*
Y-50300D01*
G01X982320Y-56133D02*
Y-38634D01*
G01Y-41258D02*
X983412Y-39800D01*
X984503Y-38925D01*
X986250Y-38634D01*
X987778Y-38925D01*
X989307Y-40383D01*
X989962Y-42425D01*
X990180Y-44467D01*
X989962Y-46509D01*
X989307Y-48550D01*
X987996Y-49717D01*
X986250Y-50300D01*
X984722Y-50008D01*
X983193Y-49134D01*
X982320Y-47967D01*
G01X1000475Y-42425D02*
X1007462D01*
X1006807Y-40383D01*
X1005715Y-39217D01*
X1004187Y-38634D01*
X1002658Y-38925D01*
X1001348Y-39800D01*
X1000475Y-41842D01*
X1000038Y-43592D01*
Y-45342D01*
X1000475Y-47092D01*
X1001567Y-48842D01*
X1002877Y-50008D01*
X1004405Y-50300D01*
X1005933Y-49717D01*
X1007462Y-47967D01*
G01X1025180Y-32800D02*
Y-50300D01*
G01Y-47676D02*
X1024307Y-49134D01*
X1022996Y-50008D01*
X1021468Y-50300D01*
X1019722Y-49717D01*
X1018412Y-48259D01*
X1017538Y-46509D01*
X1017320Y-44467D01*
X1017538Y-42425D01*
X1018412Y-40675D01*
X1019722Y-39217D01*
X1021468Y-38634D01*
X1022996Y-38925D01*
X1024088Y-39509D01*
X1025180Y-40675D01*
G01X1042680Y-50300D02*
Y-38634D01*
G01Y-40675D02*
X1041807Y-39509D01*
X1040496Y-38925D01*
X1038968Y-38634D01*
X1037440Y-39217D01*
X1036130Y-40383D01*
X1035256Y-42133D01*
X1034820Y-44467D01*
X1035256Y-46800D01*
X1036130Y-48550D01*
X1037440Y-49717D01*
X1038968Y-50300D01*
X1040496Y-50008D01*
X1041807Y-49134D01*
X1042680Y-47967D01*
G01X1052538Y-50300D02*
Y-38634D01*
G01Y-41550D02*
X1053412Y-40092D01*
X1054722Y-38925D01*
X1056468Y-38634D01*
X1057996Y-38925D01*
X1059307Y-40092D01*
X1059962Y-42133D01*
Y-50300D01*
G01X1077243Y-40092D02*
X1075715Y-38925D01*
X1074405Y-38634D01*
X1072658Y-39217D01*
X1071348Y-40383D01*
X1070475Y-42425D01*
X1070256Y-44467D01*
X1070475Y-46509D01*
X1071348Y-48259D01*
X1072658Y-49717D01*
X1074405Y-50300D01*
X1075933Y-49717D01*
X1077243Y-48550D01*
G01X1087975Y-42425D02*
X1094962D01*
X1094307Y-40383D01*
X1093215Y-39217D01*
X1091687Y-38634D01*
X1090158Y-38925D01*
X1088848Y-39800D01*
X1087975Y-41842D01*
X1087538Y-43592D01*
Y-45342D01*
X1087975Y-47092D01*
X1089067Y-48842D01*
X1090377Y-50008D01*
X1091905Y-50300D01*
X1093433Y-49717D01*
X1094962Y-47967D01*
G01X1126250Y-32800D02*
Y-50300D01*
G01X1123193Y-38634D02*
X1129307D01*
G01X1140693Y-50300D02*
Y-38634D01*
G01Y-40967D02*
X1141785Y-39800D01*
X1142877Y-38925D01*
X1144405Y-38634D01*
X1145496Y-38925D01*
X1146807Y-39800D01*
G01X1165180Y-50300D02*
Y-38634D01*
G01Y-40675D02*
X1164307Y-39509D01*
X1162996Y-38925D01*
X1161468Y-38634D01*
X1159940Y-39217D01*
X1158630Y-40383D01*
X1157756Y-42133D01*
X1157320Y-44467D01*
X1157756Y-46800D01*
X1158630Y-48550D01*
X1159940Y-49717D01*
X1161468Y-50300D01*
X1162996Y-50008D01*
X1164307Y-49134D01*
X1165180Y-47967D01*
G01X1182243Y-40092D02*
X1180715Y-38925D01*
X1179405Y-38634D01*
X1177658Y-39217D01*
X1176348Y-40383D01*
X1175475Y-42425D01*
X1175256Y-44467D01*
X1175475Y-46509D01*
X1176348Y-48259D01*
X1177658Y-49717D01*
X1179405Y-50300D01*
X1180933Y-49717D01*
X1182243Y-48550D01*
G01X1192975Y-42425D02*
X1199962D01*
X1199307Y-40383D01*
X1198215Y-39217D01*
X1196687Y-38634D01*
X1195158Y-38925D01*
X1193848Y-39800D01*
X1192975Y-41842D01*
X1192538Y-43592D01*
Y-45342D01*
X1192975Y-47092D01*
X1194067Y-48842D01*
X1195377Y-50008D01*
X1196905Y-50300D01*
X1198433Y-49717D01*
X1199962Y-47967D01*
G01X1210475Y-48259D02*
X1211567Y-49425D01*
X1213095Y-50300D01*
X1214405D01*
X1215715Y-49717D01*
X1216588Y-48842D01*
X1217025Y-47676D01*
X1216807Y-45925D01*
X1215933Y-45050D01*
X1212003Y-43300D01*
X1211130Y-41258D01*
X1211567Y-39800D01*
X1212440Y-38925D01*
X1213750Y-38634D01*
X1215060Y-38925D01*
X1216370Y-39800D01*
G01X1248750Y-38634D02*
Y-50300D01*
G01Y-33967D02*
X1248313Y-33675D01*
Y-33092D01*
X1248750Y-32800D01*
X1249187Y-33092D01*
Y-33675D01*
X1248750Y-33967D01*
G01X1262538Y-50300D02*
Y-38634D01*
G01Y-41550D02*
X1263412Y-40092D01*
X1264722Y-38925D01*
X1266468Y-38634D01*
X1267996Y-38925D01*
X1269307Y-40092D01*
X1269962Y-42133D01*
Y-50300D01*
G01X1301250D02*
Y-32800D01*
G01X1322680Y-50300D02*
Y-38634D01*
G01Y-40675D02*
X1321807Y-39509D01*
X1320496Y-38925D01*
X1318968Y-38634D01*
X1317440Y-39217D01*
X1316130Y-40383D01*
X1315256Y-42133D01*
X1314820Y-44467D01*
X1315256Y-46800D01*
X1316130Y-48550D01*
X1317440Y-49717D01*
X1318968Y-50300D01*
X1320496Y-50008D01*
X1321807Y-49134D01*
X1322680Y-47967D01*
G01X1331665Y-55550D02*
X1332975Y-56133D01*
X1334722Y-55550D01*
X1335813Y-54384D01*
X1336687Y-52925D01*
X1337996Y-48259D01*
X1340835Y-38634D01*
G01X1333848D02*
X1337996Y-48259D01*
G01X1350475Y-42425D02*
X1357462D01*
X1356807Y-40383D01*
X1355715Y-39217D01*
X1354187Y-38634D01*
X1352658Y-38925D01*
X1351348Y-39800D01*
X1350475Y-41842D01*
X1350038Y-43592D01*
Y-45342D01*
X1350475Y-47092D01*
X1351567Y-48842D01*
X1352877Y-50008D01*
X1354405Y-50300D01*
X1355933Y-49717D01*
X1357462Y-47967D01*
G01X1368193Y-50300D02*
Y-38634D01*
G01Y-40967D02*
X1369285Y-39800D01*
X1370377Y-38925D01*
X1371905Y-38634D01*
X1372996Y-38925D01*
X1374307Y-39800D01*
G01X1401883Y-32800D02*
Y-50300D01*
X1410617D01*
G01X1418947Y-46800D02*
X1420256Y-48842D01*
X1422003Y-50008D01*
X1423968Y-50300D01*
X1425715Y-50008D01*
X1427462Y-48550D01*
X1428553Y-46800D01*
X1428772Y-45050D01*
X1428335Y-43009D01*
X1426807Y-41550D01*
X1425278Y-40967D01*
X1423313D01*
G01X1425278D02*
X1426588Y-40092D01*
X1427680Y-38634D01*
X1428117Y-36884D01*
X1427680Y-35133D01*
X1426588Y-33675D01*
X1424623Y-32800D01*
X1422658Y-33092D01*
X1420693Y-34259D01*
G01X1441250Y-50883D02*
X1440813Y-50592D01*
Y-50008D01*
X1441250Y-49717D01*
X1441687Y-50008D01*
Y-50592D01*
X1441250Y-50883D01*
G01X999127Y722030D02*
X1004367D01*
G01X1001747D02*
Y704530D01*
G01X999127D02*
X1004367D01*
G01X1013570D02*
Y722030D01*
X1019247Y707447D01*
X1024924Y722030D01*
Y704530D01*
G01X1032380D02*
Y722030D01*
X1037620D01*
X1039367Y721155D01*
X1040677Y719113D01*
X1041114Y716780D01*
X1040677Y714447D01*
X1039585Y712697D01*
X1037620Y711821D01*
X1032380D01*
G01X1053155Y698697D02*
X1050972Y701613D01*
X1049880Y704530D01*
Y716196D01*
X1050972Y719113D01*
X1053155Y722030D01*
G01X1071747Y704530D02*
X1070000Y704822D01*
X1068472Y705988D01*
X1067162Y707738D01*
X1066288Y709780D01*
X1065852Y712113D01*
Y714447D01*
X1066288Y716780D01*
X1067162Y718822D01*
X1068472Y720571D01*
X1070000Y721738D01*
X1071747Y722030D01*
X1073493Y721738D01*
X1075022Y720571D01*
X1076332Y718822D01*
X1077206Y716780D01*
X1077642Y714447D01*
Y712113D01*
X1077206Y709780D01*
X1076332Y707738D01*
X1075022Y705988D01*
X1073493Y704822D01*
X1071747Y704530D01*
G01X1085535D02*
Y722030D01*
G01Y713572D02*
X1086627Y715030D01*
X1087719Y715905D01*
X1089465Y716196D01*
X1090775Y715905D01*
X1092304Y714738D01*
X1092959Y712988D01*
Y704530D01*
G01X1100197D02*
Y716196D01*
G01Y712988D02*
X1100852Y714447D01*
X1101944Y715613D01*
X1103472Y716196D01*
X1105000Y715613D01*
X1106092Y714447D01*
X1106747Y712988D01*
Y704530D01*
G01Y712988D02*
X1107402Y714447D01*
X1108493Y715613D01*
X1110022Y716196D01*
X1111550Y715613D01*
X1112642Y714447D01*
X1113297Y712697D01*
Y704530D01*
G01X1125339Y698697D02*
X1127522Y701613D01*
X1128614Y704530D01*
Y716196D01*
X1127522Y719113D01*
X1125339Y722030D01*
G01X977244Y739180D02*
Y756680D01*
X981610D01*
X983357Y755805D01*
X984667Y754638D01*
X985759Y752889D01*
X986632Y750846D01*
X986850Y747930D01*
X986632Y745013D01*
X985759Y742971D01*
X984667Y741221D01*
X983357Y740055D01*
X981610Y739180D01*
X977244D01*
G01X995180D02*
Y756680D01*
X1000420D01*
X1002167Y755805D01*
X1003477Y753763D01*
X1003914Y751430D01*
X1003477Y749097D01*
X1002385Y747347D01*
X1000420Y746471D01*
X995180D01*
G01X1031927Y756680D02*
X1037167D01*
G01X1034547D02*
Y739180D01*
G01X1031927D02*
X1037167D01*
G01X1046370D02*
Y756680D01*
X1052047Y742097D01*
X1057724Y756680D01*
Y739180D01*
G01X1065180D02*
Y756680D01*
X1070420D01*
X1072167Y755805D01*
X1073477Y753763D01*
X1073914Y751430D01*
X1073477Y749097D01*
X1072385Y747347D01*
X1070420Y746471D01*
X1065180D01*
G01X1091414Y739180D02*
X1082680D01*
Y756680D01*
X1091414D01*
G01X1087920Y748222D02*
X1082680D01*
G01X1099744Y739180D02*
Y756680D01*
X1104110D01*
X1105857Y755805D01*
X1107167Y754638D01*
X1108259Y752889D01*
X1109132Y750846D01*
X1109350Y747930D01*
X1109132Y745013D01*
X1108259Y742971D01*
X1107167Y741221D01*
X1105857Y740055D01*
X1104110Y739180D01*
X1099744D01*
G01X1116588D02*
X1122047Y756680D01*
X1127506Y739180D01*
G01X1125540Y745305D02*
X1118553D01*
G01X1134525Y739180D02*
Y756680D01*
X1144569Y739180D01*
Y756680D01*
G01X1161850Y755221D02*
X1160540Y756097D01*
X1159012Y756680D01*
X1157265D01*
X1155300Y755805D01*
X1153772Y754347D01*
X1152680Y752596D01*
X1151807Y749680D01*
X1151588Y747055D01*
X1152025Y744430D01*
X1152680Y742680D01*
X1153990Y740930D01*
X1155519Y739763D01*
X1157047Y739180D01*
X1158575D01*
X1160104Y739763D01*
X1161414Y740638D01*
X1162506Y741804D01*
G01X1178914Y739180D02*
X1170180D01*
Y756680D01*
X1178914D01*
G01X1175420Y748222D02*
X1170180D01*
G01X1209547Y756680D02*
Y739180D01*
G01X1204525Y756680D02*
X1214569D01*
G01X1221588Y739180D02*
X1227047Y756680D01*
X1232506Y739180D01*
G01X1230540Y745305D02*
X1223553D01*
G01X1246293Y748513D02*
X1247167Y749388D01*
X1247822Y750846D01*
X1248259Y752889D01*
X1247822Y754638D01*
X1246949Y755805D01*
X1245420Y756680D01*
X1239525D01*
Y739180D01*
X1246730D01*
X1248259Y740346D01*
X1249132Y742097D01*
X1249569Y744138D01*
X1249132Y746180D01*
X1247822Y747930D01*
X1246293Y748513D01*
X1239525D01*
G01X1257680Y756680D02*
Y739180D01*
X1266414D01*
G01X1283914D02*
X1275180D01*
Y756680D01*
X1283914D01*
G01X1280420Y748222D02*
X1275180D01*
G01X1297047Y738597D02*
X1296610Y738888D01*
Y739472D01*
X1297047Y739763D01*
X1297484Y739472D01*
Y738888D01*
X1297047Y738597D01*
G01Y746471D02*
X1296610Y746763D01*
Y747347D01*
X1297047Y747638D01*
X1297484Y747347D01*
Y746763D01*
X1297047Y746471D01*
G01X1327680Y756680D02*
Y739180D01*
X1336414D01*
G01X1344744Y742680D02*
X1346053Y740638D01*
X1347800Y739472D01*
X1349765Y739180D01*
X1351512Y739472D01*
X1353259Y740930D01*
X1354350Y742680D01*
X1354569Y744430D01*
X1354132Y746471D01*
X1352604Y747930D01*
X1351075Y748513D01*
X1349110D01*
G01X1351075D02*
X1352385Y749388D01*
X1353477Y750846D01*
X1353914Y752596D01*
X1353477Y754347D01*
X1352385Y755805D01*
X1350420Y756680D01*
X1348455Y756388D01*
X1346490Y755221D01*
G01X1027997Y635230D02*
Y652730D01*
X1025377Y649230D01*
G01Y635230D02*
X1030617D01*
G01X1045497Y652730D02*
X1043750Y652147D01*
X1042440Y650688D01*
X1041567Y648939D01*
X1040912Y646605D01*
X1040694Y643980D01*
X1040912Y641355D01*
X1041567Y639021D01*
X1042440Y637271D01*
X1043750Y635813D01*
X1045497Y635230D01*
X1047243Y635813D01*
X1048554Y637271D01*
X1049427Y639021D01*
X1050082Y641355D01*
X1050300Y643980D01*
X1050082Y646605D01*
X1049427Y648939D01*
X1048554Y650688D01*
X1047243Y652147D01*
X1045497Y652730D01*
G01X1062997D02*
X1061250Y652147D01*
X1059940Y650688D01*
X1059067Y648939D01*
X1058412Y646605D01*
X1058194Y643980D01*
X1058412Y641355D01*
X1059067Y639021D01*
X1059940Y637271D01*
X1061250Y635813D01*
X1062997Y635230D01*
X1064743Y635813D01*
X1066054Y637271D01*
X1066927Y639021D01*
X1067582Y641355D01*
X1067800Y643980D01*
X1067582Y646605D01*
X1066927Y648939D01*
X1066054Y650688D01*
X1064743Y652147D01*
X1062997Y652730D01*
G01X1080497Y634647D02*
X1080060Y634938D01*
Y635522D01*
X1080497Y635813D01*
X1080934Y635522D01*
Y634938D01*
X1080497Y634647D01*
G01X1097997Y652730D02*
X1096250Y652147D01*
X1094940Y650688D01*
X1094067Y648939D01*
X1093412Y646605D01*
X1093194Y643980D01*
X1093412Y641355D01*
X1094067Y639021D01*
X1094940Y637271D01*
X1096250Y635813D01*
X1097997Y635230D01*
X1099743Y635813D01*
X1101054Y637271D01*
X1101927Y639021D01*
X1102582Y641355D01*
X1102800Y643980D01*
X1102582Y646605D01*
X1101927Y648939D01*
X1101054Y650688D01*
X1099743Y652147D01*
X1097997Y652730D01*
G01X1036747Y669880D02*
X1038275Y670172D01*
X1040022Y671046D01*
X1041114Y672504D01*
X1041550Y674547D01*
X1041114Y676588D01*
X1039804Y678338D01*
X1037839Y679213D01*
X1035655D01*
X1034345Y679797D01*
X1033253Y681255D01*
X1032817Y683296D01*
X1033472Y685338D01*
X1035000Y686797D01*
X1036747Y687380D01*
X1038493Y686797D01*
X1040022Y685338D01*
X1040677Y683296D01*
X1040240Y681255D01*
X1039149Y679797D01*
X1037839Y679213D01*
X1035655D01*
X1033690Y678338D01*
X1032380Y676588D01*
X1031944Y674547D01*
X1032380Y672504D01*
X1033472Y671046D01*
X1035219Y670172D01*
X1036747Y669880D01*
G01X1049444Y672504D02*
X1050753Y671046D01*
X1052282Y670172D01*
X1054247Y669880D01*
X1056212Y670463D01*
X1057740Y671630D01*
X1058832Y673671D01*
X1059050Y676005D01*
X1058614Y678338D01*
X1057522Y679797D01*
X1055993Y680963D01*
X1054465Y681255D01*
X1052937Y680963D01*
X1050972Y679797D01*
X1051627Y687380D01*
X1057522D01*
G01X1071747Y669297D02*
X1071310Y669588D01*
Y670172D01*
X1071747Y670463D01*
X1072184Y670172D01*
Y669588D01*
X1071747Y669297D01*
G01X1089247Y687380D02*
X1087500Y686797D01*
X1086190Y685338D01*
X1085317Y683589D01*
X1084662Y681255D01*
X1084444Y678630D01*
X1084662Y676005D01*
X1085317Y673671D01*
X1086190Y671921D01*
X1087500Y670463D01*
X1089247Y669880D01*
X1090993Y670463D01*
X1092304Y671921D01*
X1093177Y673671D01*
X1093832Y676005D01*
X1094050Y678630D01*
X1093832Y681255D01*
X1093177Y683589D01*
X1092304Y685338D01*
X1090993Y686797D01*
X1089247Y687380D01*
G01X1205197Y722030D02*
X1208253Y704530D01*
X1211747Y722030D01*
X1215240Y704530D01*
X1218297Y722030D01*
G01X1226627D02*
X1231867D01*
G01X1229247D02*
Y704530D01*
G01X1226627D02*
X1231867D01*
G01X1241944D02*
Y722030D01*
X1246310D01*
X1248057Y721155D01*
X1249367Y719988D01*
X1250459Y718239D01*
X1251332Y716196D01*
X1251550Y713280D01*
X1251332Y710363D01*
X1250459Y708321D01*
X1249367Y706571D01*
X1248057Y705405D01*
X1246310Y704530D01*
X1241944D01*
G01X1264247Y722030D02*
Y704530D01*
G01X1259225Y722030D02*
X1269269D01*
G01X1277162Y704530D02*
Y722030D01*
G01X1286332D02*
Y704530D01*
G01Y713280D02*
X1277162D01*
G01X1298155Y698697D02*
X1295972Y701613D01*
X1294880Y704530D01*
Y716196D01*
X1295972Y719113D01*
X1298155Y722030D01*
G01X1310197Y704530D02*
Y716196D01*
G01Y712988D02*
X1310852Y714447D01*
X1311944Y715613D01*
X1313472Y716196D01*
X1315000Y715613D01*
X1316092Y714447D01*
X1316747Y712988D01*
Y704530D01*
G01Y712988D02*
X1317402Y714447D01*
X1318493Y715613D01*
X1320022Y716196D01*
X1321550Y715613D01*
X1322642Y714447D01*
X1323297Y712697D01*
Y704530D01*
G01X1334247Y716196D02*
Y704530D01*
G01Y720863D02*
X1333810Y721155D01*
Y721738D01*
X1334247Y722030D01*
X1334684Y721738D01*
Y721155D01*
X1334247Y720863D01*
G01X1351747Y704530D02*
Y722030D01*
G01X1365972Y706571D02*
X1367064Y705405D01*
X1368592Y704530D01*
X1369902D01*
X1371212Y705113D01*
X1372085Y705988D01*
X1372522Y707154D01*
X1372304Y708905D01*
X1371430Y709780D01*
X1367500Y711530D01*
X1366627Y713572D01*
X1367064Y715030D01*
X1367937Y715905D01*
X1369247Y716196D01*
X1370557Y715905D01*
X1371867Y715030D01*
G01X1387839Y698697D02*
X1390022Y701613D01*
X1391114Y704530D01*
Y716196D01*
X1390022Y719113D01*
X1387839Y722030D01*
G01X1249367Y635230D02*
Y652730D01*
X1241288Y640188D01*
X1252206D01*
G01X1264247Y634647D02*
X1263810Y634938D01*
Y635522D01*
X1264247Y635813D01*
X1264684Y635522D01*
Y634938D01*
X1264247Y634647D01*
G01X1281747Y652730D02*
X1280000Y652147D01*
X1278690Y650688D01*
X1277817Y648939D01*
X1277162Y646605D01*
X1276944Y643980D01*
X1277162Y641355D01*
X1277817Y639021D01*
X1278690Y637271D01*
X1280000Y635813D01*
X1281747Y635230D01*
X1283493Y635813D01*
X1284804Y637271D01*
X1285677Y639021D01*
X1286332Y641355D01*
X1286550Y643980D01*
X1286332Y646605D01*
X1285677Y648939D01*
X1284804Y650688D01*
X1283493Y652147D01*
X1281747Y652730D01*
G01X1295317Y634647D02*
X1303177Y652730D01*
G01X1316747Y635230D02*
X1318275Y635522D01*
X1320022Y636396D01*
X1321114Y637854D01*
X1321550Y639897D01*
X1321114Y641938D01*
X1319804Y643688D01*
X1317839Y644563D01*
X1315655D01*
X1314345Y645147D01*
X1313253Y646605D01*
X1312817Y648646D01*
X1313472Y650688D01*
X1315000Y652147D01*
X1316747Y652730D01*
X1318493Y652147D01*
X1320022Y650688D01*
X1320677Y648646D01*
X1320240Y646605D01*
X1319149Y645147D01*
X1317839Y644563D01*
X1315655D01*
X1313690Y643688D01*
X1312380Y641938D01*
X1311944Y639897D01*
X1312380Y637854D01*
X1313472Y636396D01*
X1315219Y635522D01*
X1316747Y635230D01*
G01X1334247Y634647D02*
X1333810Y634938D01*
Y635522D01*
X1334247Y635813D01*
X1334684Y635522D01*
Y634938D01*
X1334247Y634647D01*
G01X1351747Y652730D02*
X1350000Y652147D01*
X1348690Y650688D01*
X1347817Y648939D01*
X1347162Y646605D01*
X1346944Y643980D01*
X1347162Y641355D01*
X1347817Y639021D01*
X1348690Y637271D01*
X1350000Y635813D01*
X1351747Y635230D01*
X1353493Y635813D01*
X1354804Y637271D01*
X1355677Y639021D01*
X1356332Y641355D01*
X1356550Y643980D01*
X1356332Y646605D01*
X1355677Y648939D01*
X1354804Y650688D01*
X1353493Y652147D01*
X1351747Y652730D01*
G01X1241944Y672504D02*
X1243253Y671046D01*
X1244782Y670172D01*
X1246747Y669880D01*
X1248712Y670463D01*
X1250240Y671630D01*
X1251332Y673671D01*
X1251550Y676005D01*
X1251114Y678338D01*
X1250022Y679797D01*
X1248493Y680963D01*
X1246965Y681255D01*
X1245437Y680963D01*
X1243472Y679797D01*
X1244127Y687380D01*
X1250022D01*
G01X1264247Y669297D02*
X1263810Y669588D01*
Y670172D01*
X1264247Y670463D01*
X1264684Y670172D01*
Y669588D01*
X1264247Y669297D01*
G01X1276944Y672504D02*
X1278253Y671046D01*
X1279782Y670172D01*
X1281747Y669880D01*
X1283712Y670463D01*
X1285240Y671630D01*
X1286332Y673671D01*
X1286550Y676005D01*
X1286114Y678338D01*
X1285022Y679797D01*
X1283493Y680963D01*
X1281965Y681255D01*
X1280437Y680963D01*
X1278472Y679797D01*
X1279127Y687380D01*
X1285022D01*
G01X1295317Y669297D02*
X1303177Y687380D01*
G01X1316310Y669880D02*
X1316747Y673671D01*
X1317402Y676880D01*
X1318275Y679797D01*
X1319367Y683005D01*
X1321114Y687380D01*
X1312380D01*
G01X1334247Y669297D02*
X1333810Y669588D01*
Y670172D01*
X1334247Y670463D01*
X1334684Y670172D01*
Y669588D01*
X1334247Y669297D01*
G01X1346944Y672504D02*
X1348253Y671046D01*
X1349782Y670172D01*
X1351747Y669880D01*
X1353712Y670463D01*
X1355240Y671630D01*
X1356332Y673671D01*
X1356550Y676005D01*
X1356114Y678338D01*
X1355022Y679797D01*
X1353493Y680963D01*
X1351965Y681255D01*
X1350437Y680963D01*
X1348472Y679797D01*
X1349127Y687380D01*
X1355022D01*
G01X1486944Y635230D02*
Y652730D01*
X1491310D01*
X1493057Y651855D01*
X1494367Y650688D01*
X1495459Y648939D01*
X1496332Y646896D01*
X1496550Y643980D01*
X1496332Y641063D01*
X1495459Y639021D01*
X1494367Y637271D01*
X1493057Y636105D01*
X1491310Y635230D01*
X1486944D01*
G01X1504880D02*
Y652730D01*
X1510120D01*
X1511867Y651855D01*
X1513177Y649813D01*
X1513614Y647480D01*
X1513177Y645147D01*
X1512085Y643397D01*
X1510120Y642521D01*
X1504880D01*
G01X1474247Y722030D02*
Y704530D01*
G01X1469225Y722030D02*
X1479269D01*
G01X1491747Y704530D02*
Y712405D01*
X1487380Y722030D01*
G01X1496114D02*
X1491747Y712405D01*
G01X1504880Y704530D02*
Y722030D01*
X1510120D01*
X1511867Y721155D01*
X1513177Y719113D01*
X1513614Y716780D01*
X1513177Y714447D01*
X1512085Y712697D01*
X1510120Y711821D01*
X1504880D01*
G01X1531114Y704530D02*
X1522380D01*
Y722030D01*
X1531114D01*
G01X1527620Y713572D02*
X1522380D01*
G01X1486944Y669880D02*
Y687380D01*
X1491310D01*
X1493057Y686505D01*
X1494367Y685338D01*
X1495459Y683589D01*
X1496332Y681546D01*
X1496550Y678630D01*
X1496332Y675713D01*
X1495459Y673671D01*
X1494367Y671921D01*
X1493057Y670755D01*
X1491310Y669880D01*
X1486944D01*
G01X1504880D02*
Y687380D01*
X1510120D01*
X1511867Y686505D01*
X1513177Y684463D01*
X1513614Y682130D01*
X1513177Y679797D01*
X1512085Y678047D01*
X1510120Y677171D01*
X1504880D01*
G01X1574880Y704530D02*
Y722030D01*
X1580339D01*
X1582085Y721155D01*
X1583177Y719988D01*
X1583614Y717655D01*
X1583177Y715321D01*
X1581867Y713863D01*
X1580339Y712988D01*
X1574880D01*
G01X1580339D02*
X1583614Y704530D01*
G01X1593472Y712405D02*
X1600459D01*
X1599804Y714447D01*
X1598712Y715613D01*
X1597184Y716196D01*
X1595655Y715905D01*
X1594345Y715030D01*
X1593472Y712988D01*
X1593035Y711238D01*
Y709488D01*
X1593472Y707738D01*
X1594564Y705988D01*
X1595874Y704822D01*
X1597402Y704530D01*
X1598930Y705113D01*
X1600459Y706863D01*
G01X1612937Y704530D02*
Y719405D01*
X1613374Y720863D01*
X1614247Y721738D01*
X1615557Y722030D01*
X1616867Y721447D01*
X1617522Y719988D01*
G01X1614902Y715030D02*
X1610535D01*
G01X1631747Y703947D02*
X1631310Y704238D01*
Y704822D01*
X1631747Y705113D01*
X1632184Y704822D01*
Y704238D01*
X1631747Y703947D01*
G01X1662380Y704530D02*
Y722030D01*
X1667620D01*
X1669367Y721155D01*
X1670677Y719113D01*
X1671114Y716780D01*
X1670677Y714447D01*
X1669585Y712697D01*
X1667620Y711821D01*
X1662380D01*
G01X1684247Y704530D02*
Y722030D01*
G01X1705677Y704530D02*
Y716196D01*
G01Y714155D02*
X1704804Y715321D01*
X1703493Y715905D01*
X1701965Y716196D01*
X1700437Y715613D01*
X1699127Y714447D01*
X1698253Y712697D01*
X1697817Y710363D01*
X1698253Y708030D01*
X1699127Y706280D01*
X1700437Y705113D01*
X1701965Y704530D01*
X1703493Y704822D01*
X1704804Y705696D01*
X1705677Y706863D01*
G01X1715535Y704530D02*
Y716196D01*
G01Y713280D02*
X1716409Y714738D01*
X1717719Y715905D01*
X1719465Y716196D01*
X1720993Y715905D01*
X1722304Y714738D01*
X1722959Y712697D01*
Y704530D01*
G01X1733472Y712405D02*
X1740459D01*
X1739804Y714447D01*
X1738712Y715613D01*
X1737184Y716196D01*
X1735655Y715905D01*
X1734345Y715030D01*
X1733472Y712988D01*
X1733035Y711238D01*
Y709488D01*
X1733472Y707738D01*
X1734564Y705988D01*
X1735874Y704822D01*
X1737402Y704530D01*
X1738930Y705113D01*
X1740459Y706863D01*
G01X1618630Y652730D02*
Y635230D01*
X1627364D01*
G01X1636349Y649813D02*
X1637659Y651563D01*
X1639187Y652438D01*
X1640934Y652730D01*
X1643117Y652147D01*
X1644645Y650688D01*
X1645082Y648939D01*
X1644864Y647188D01*
X1643990Y645730D01*
X1639624Y642813D01*
X1637659Y640772D01*
X1636349Y637854D01*
X1635912Y635230D01*
X1645082D01*
G01X1654067Y634647D02*
X1661927Y652730D01*
G01X1671130D02*
Y635230D01*
X1679864D01*
G01X1695617D02*
Y652730D01*
X1687538Y640188D01*
X1698456D01*
G01X1618630Y687380D02*
Y669880D01*
X1627364D01*
G01X1636349Y684463D02*
X1637659Y686213D01*
X1639187Y687088D01*
X1640934Y687380D01*
X1643117Y686797D01*
X1644645Y685338D01*
X1645082Y683589D01*
X1644864Y681838D01*
X1643990Y680380D01*
X1639624Y677463D01*
X1637659Y675422D01*
X1636349Y672504D01*
X1635912Y669880D01*
X1645082D01*
G01X1654067Y669297D02*
X1661927Y687380D01*
G01X1671130D02*
Y669880D01*
X1679864D01*
G01X1695617D02*
Y687380D01*
X1687538Y674838D01*
X1698456D01*
G01X1779744Y703947D02*
X1789350Y716780D01*
G01X1784547Y719113D02*
Y701613D01*
G01X1789350Y703947D02*
X1779744Y716780D01*
G01X1777997Y710363D02*
X1791097D01*
G01X1816709D02*
X1822385D01*
G01X1849744Y704530D02*
Y722030D01*
X1854110D01*
X1855857Y721155D01*
X1857167Y719988D01*
X1858259Y718239D01*
X1859132Y716196D01*
X1859350Y713280D01*
X1859132Y710363D01*
X1858259Y708321D01*
X1857167Y706571D01*
X1855857Y705405D01*
X1854110Y704530D01*
X1849744D01*
G01X1868772Y712405D02*
X1875759D01*
X1875104Y714447D01*
X1874012Y715613D01*
X1872484Y716196D01*
X1870955Y715905D01*
X1869645Y715030D01*
X1868772Y712988D01*
X1868335Y711238D01*
Y709488D01*
X1868772Y707738D01*
X1869864Y705988D01*
X1871174Y704822D01*
X1872702Y704530D01*
X1874230Y705113D01*
X1875759Y706863D01*
G01X1885835Y704530D02*
Y716196D01*
G01Y713280D02*
X1886709Y714738D01*
X1888019Y715905D01*
X1889765Y716196D01*
X1891293Y715905D01*
X1892604Y714738D01*
X1893259Y712697D01*
Y704530D01*
G01X1907047D02*
X1905737Y704822D01*
X1904427Y705988D01*
X1903553Y708030D01*
X1903117Y710363D01*
X1903553Y712697D01*
X1904427Y714738D01*
X1905737Y715905D01*
X1907047Y716196D01*
X1908357Y715905D01*
X1909667Y714738D01*
X1910540Y712697D01*
X1910759Y710363D01*
X1910540Y708030D01*
X1909667Y705988D01*
X1908357Y704822D01*
X1907047Y704530D01*
G01X1924547Y722030D02*
Y704530D01*
G01X1921490Y716196D02*
X1927604D01*
G01X1938772Y712405D02*
X1945759D01*
X1945104Y714447D01*
X1944012Y715613D01*
X1942484Y716196D01*
X1940955Y715905D01*
X1939645Y715030D01*
X1938772Y712988D01*
X1938335Y711238D01*
Y709488D01*
X1938772Y707738D01*
X1939864Y705988D01*
X1941174Y704822D01*
X1942702Y704530D01*
X1944230Y705113D01*
X1945759Y706863D01*
G01X1956272Y706571D02*
X1957364Y705405D01*
X1958892Y704530D01*
X1960202D01*
X1961512Y705113D01*
X1962385Y705988D01*
X1962822Y707154D01*
X1962604Y708905D01*
X1961730Y709780D01*
X1957800Y711530D01*
X1956927Y713572D01*
X1957364Y715030D01*
X1958237Y715905D01*
X1959547Y716196D01*
X1960857Y715905D01*
X1962167Y715030D01*
G01X1994547Y722030D02*
Y704530D01*
G01X1991490Y716196D02*
X1997604D01*
G01X2008335Y704530D02*
Y722030D01*
G01Y713572D02*
X2009427Y715030D01*
X2010519Y715905D01*
X2012265Y716196D01*
X2013575Y715905D01*
X2015104Y714738D01*
X2015759Y712988D01*
Y704530D01*
G01X2033477D02*
Y716196D01*
G01Y714155D02*
X2032604Y715321D01*
X2031293Y715905D01*
X2029765Y716196D01*
X2028237Y715613D01*
X2026927Y714447D01*
X2026053Y712697D01*
X2025617Y710363D01*
X2026053Y708030D01*
X2026927Y706280D01*
X2028237Y705113D01*
X2029765Y704530D01*
X2031293Y704822D01*
X2032604Y705696D01*
X2033477Y706863D01*
G01X2047047Y722030D02*
Y704530D01*
G01X2043990Y716196D02*
X2050104D01*
G01X2082047Y722030D02*
Y704530D01*
G01X2078990Y716196D02*
X2085104D01*
G01X2095835Y704530D02*
Y722030D01*
G01Y713572D02*
X2096927Y715030D01*
X2098019Y715905D01*
X2099765Y716196D01*
X2101075Y715905D01*
X2102604Y714738D01*
X2103259Y712988D01*
Y704530D01*
G01X2117047Y716196D02*
Y704530D01*
G01Y720863D02*
X2116610Y721155D01*
Y721738D01*
X2117047Y722030D01*
X2117484Y721738D01*
Y721155D01*
X2117047Y720863D01*
G01X2131272Y706571D02*
X2132364Y705405D01*
X2133892Y704530D01*
X2135202D01*
X2136512Y705113D01*
X2137385Y705988D01*
X2137822Y707154D01*
X2137604Y708905D01*
X2136730Y709780D01*
X2132800Y711530D01*
X2131927Y713572D01*
X2132364Y715030D01*
X2133237Y715905D01*
X2134547Y716196D01*
X2135857Y715905D01*
X2137167Y715030D01*
G01X2166927Y722030D02*
X2172167D01*
G01X2169547D02*
Y704530D01*
G01X2166927D02*
X2172167D01*
G01X2180497D02*
Y716196D01*
G01Y712988D02*
X2181152Y714447D01*
X2182244Y715613D01*
X2183772Y716196D01*
X2185300Y715613D01*
X2186392Y714447D01*
X2187047Y712988D01*
Y704530D01*
G01Y712988D02*
X2187702Y714447D01*
X2188793Y715613D01*
X2190322Y716196D01*
X2191850Y715613D01*
X2192942Y714447D01*
X2193597Y712697D01*
Y704530D01*
G01X2200617Y698697D02*
Y716196D01*
G01Y713572D02*
X2201709Y715030D01*
X2202800Y715905D01*
X2204547Y716196D01*
X2206075Y715905D01*
X2207604Y714447D01*
X2208259Y712405D01*
X2208477Y710363D01*
X2208259Y708321D01*
X2207604Y706280D01*
X2206293Y705113D01*
X2204547Y704530D01*
X2203019Y704822D01*
X2201490Y705696D01*
X2200617Y706863D01*
G01X2218772Y712405D02*
X2225759D01*
X2225104Y714447D01*
X2224012Y715613D01*
X2222484Y716196D01*
X2220955Y715905D01*
X2219645Y715030D01*
X2218772Y712988D01*
X2218335Y711238D01*
Y709488D01*
X2218772Y707738D01*
X2219864Y705988D01*
X2221174Y704822D01*
X2222702Y704530D01*
X2224230Y705113D01*
X2225759Y706863D01*
G01X2243477Y722030D02*
Y704530D01*
G01Y707154D02*
X2242604Y705696D01*
X2241293Y704822D01*
X2239765Y704530D01*
X2238019Y705113D01*
X2236709Y706571D01*
X2235835Y708321D01*
X2235617Y710363D01*
X2235835Y712405D01*
X2236709Y714155D01*
X2238019Y715613D01*
X2239765Y716196D01*
X2241293Y715905D01*
X2242385Y715321D01*
X2243477Y714155D01*
G01X2260977Y704530D02*
Y716196D01*
G01Y714155D02*
X2260104Y715321D01*
X2258793Y715905D01*
X2257265Y716196D01*
X2255737Y715613D01*
X2254427Y714447D01*
X2253553Y712697D01*
X2253117Y710363D01*
X2253553Y708030D01*
X2254427Y706280D01*
X2255737Y705113D01*
X2257265Y704530D01*
X2258793Y704822D01*
X2260104Y705696D01*
X2260977Y706863D01*
G01X2270835Y704530D02*
Y716196D01*
G01Y713280D02*
X2271709Y714738D01*
X2273019Y715905D01*
X2274765Y716196D01*
X2276293Y715905D01*
X2277604Y714738D01*
X2278259Y712697D01*
Y704530D01*
G01X2295540Y714738D02*
X2294012Y715905D01*
X2292702Y716196D01*
X2290955Y715613D01*
X2289645Y714447D01*
X2288772Y712405D01*
X2288553Y710363D01*
X2288772Y708321D01*
X2289645Y706571D01*
X2290955Y705113D01*
X2292702Y704530D01*
X2294230Y705113D01*
X2295540Y706280D01*
G01X2306272Y712405D02*
X2313259D01*
X2312604Y714447D01*
X2311512Y715613D01*
X2309984Y716196D01*
X2308455Y715905D01*
X2307145Y715030D01*
X2306272Y712988D01*
X2305835Y711238D01*
Y709488D01*
X2306272Y707738D01*
X2307364Y705988D01*
X2308674Y704822D01*
X2310202Y704530D01*
X2311730Y705113D01*
X2313259Y706863D01*
G01X1854547Y681546D02*
Y669880D01*
G01Y686213D02*
X1854110Y686505D01*
Y687088D01*
X1854547Y687380D01*
X1854984Y687088D01*
Y686505D01*
X1854547Y686213D01*
G01X1868772Y671921D02*
X1869864Y670755D01*
X1871392Y669880D01*
X1872702D01*
X1874012Y670463D01*
X1874885Y671338D01*
X1875322Y672504D01*
X1875104Y674255D01*
X1874230Y675130D01*
X1870300Y676880D01*
X1869427Y678922D01*
X1869864Y680380D01*
X1870737Y681255D01*
X1872047Y681546D01*
X1873357Y681255D01*
X1874667Y680380D01*
G01X1902025Y669880D02*
Y687380D01*
X1912069Y669880D01*
Y687380D01*
G01X1924547Y669880D02*
X1922800Y670172D01*
X1921272Y671338D01*
X1919962Y673088D01*
X1919088Y675130D01*
X1918652Y677463D01*
Y679797D01*
X1919088Y682130D01*
X1919962Y684172D01*
X1921272Y685921D01*
X1922800Y687088D01*
X1924547Y687380D01*
X1926293Y687088D01*
X1927822Y685921D01*
X1929132Y684172D01*
X1930006Y682130D01*
X1930442Y679797D01*
Y677463D01*
X1930006Y675130D01*
X1929132Y673088D01*
X1927822Y671338D01*
X1926293Y670172D01*
X1924547Y669880D01*
G01X1942047Y687380D02*
Y669880D01*
G01X1937025Y687380D02*
X1947069D01*
G01X1973335Y681546D02*
Y673380D01*
X1974209Y671338D01*
X1975519Y670172D01*
X1977047Y669880D01*
X1978575Y670172D01*
X1979885Y671338D01*
X1980759Y673380D01*
G01Y669880D02*
Y681546D01*
G01X1991272Y671921D02*
X1992364Y670755D01*
X1993892Y669880D01*
X1995202D01*
X1996512Y670463D01*
X1997385Y671338D01*
X1997822Y672504D01*
X1997604Y674255D01*
X1996730Y675130D01*
X1992800Y676880D01*
X1991927Y678922D01*
X1992364Y680380D01*
X1993237Y681255D01*
X1994547Y681546D01*
X1995857Y681255D01*
X1997167Y680380D01*
G01X2008772Y677755D02*
X2015759D01*
X2015104Y679797D01*
X2014012Y680963D01*
X2012484Y681546D01*
X2010955Y681255D01*
X2009645Y680380D01*
X2008772Y678338D01*
X2008335Y676588D01*
Y674838D01*
X2008772Y673088D01*
X2009864Y671338D01*
X2011174Y670172D01*
X2012702Y669880D01*
X2014230Y670463D01*
X2015759Y672213D01*
G01X2033477Y687380D02*
Y669880D01*
G01Y672504D02*
X2032604Y671046D01*
X2031293Y670172D01*
X2029765Y669880D01*
X2028019Y670463D01*
X2026709Y671921D01*
X2025835Y673671D01*
X2025617Y675713D01*
X2025835Y677755D01*
X2026709Y679505D01*
X2028019Y680963D01*
X2029765Y681546D01*
X2031293Y681255D01*
X2032385Y680671D01*
X2033477Y679505D01*
G01X3937Y0D02*
X116260D01*
G01X0Y3937D02*
G03X3937Y0I3937J0D01*
G01X0Y723480D02*
Y3937D01*
G01X416Y725241D02*
G03X0Y723480I3521J-1761D01*
G01X18597Y761603D02*
X416Y725241D01*
G01X22118Y763780D02*
G03X18597Y761603I1J-3937D01*
G01X386149Y763780D02*
X22118D01*
G01X120197Y3937D02*
Y429331D01*
G01X116260Y0D02*
G03X120197Y3937I0J3937D01*
G01X128071D02*
G03X132008Y0I3937J0D01*
G01X128071Y43308D02*
G03X120197I-3937J0D01*
G01X132008Y0D02*
X275709D01*
G01X128071Y3937D02*
Y43308D01*
G01X120197Y74016D02*
G03X128071I3937J0D01*
G01D02*
Y425394D01*
G01X124134Y433268D02*
X283583D01*
G01X124134D02*
G03X120197Y429331I0J-3937D01*
G01X188504Y425394D02*
X128071D01*
G01X152497Y21054D02*
G03I-4291J0D01*
G01X188504Y425394D02*
G03Y433268I0J3937D01*
G01X275709Y0D02*
G03X279646Y3937I0J3937D01*
G01X287520Y43308D02*
G03X279646I-3937J0D01*
G01Y3937D02*
Y43308D01*
G01Y74016D02*
G03X287520I3937J0D01*
G01X279646D02*
Y425394D01*
G01X265438Y405580D02*
G03I-4291J0D01*
G01X287520Y429331D02*
G03X283583Y433268I-3937J0D01*
G01X219213D02*
G03Y425394I0J-3937D01*
G01X279646D02*
X219213D01*
G01X291457Y0D02*
X921260D01*
G01X287520Y3937D02*
G03X291457Y0I3937J0D01*
G01X287520Y429331D02*
Y3937D01*
G01X408268Y188976D02*
Y723480D01*
G01Y188976D02*
G03X412205I1968J0D01*
G01X564173D02*
X412205D01*
G01X416142Y348379D02*
Y196851D01*
G01D02*
X560237D01*
G01X416142Y348379D02*
G03X408268I-3937J0D01*
G01Y379088D02*
G03X416142I3937J0D01*
G01Y688303D02*
Y379088D01*
G01Y688303D02*
G03X408268I-3937J0D01*
G01X389671Y761603D02*
G03X386149Y763780I-3522J-1760D01*
G01X407852Y725241D02*
X389671Y761603D01*
G01X408268Y723480D02*
G03X407852Y725241I-3937J0D01*
G01X524242Y763780D02*
X403757D01*
G01D02*
G03X400235Y758082I0J-3937D01*
G01X408268Y719012D02*
G03X416142I3937J0D01*
G01Y723480D02*
G03X414895Y728763I-11811J1D01*
G01X400235Y758082D02*
X414895Y728763D01*
G01X416142Y723480D02*
Y719012D01*
G01X490789Y356293D02*
G03I-4291J0D01*
G01X564173Y188976D02*
G03X568110I1968J0D01*
G01Y589622D02*
Y188976D01*
G01X560237Y261975D02*
Y196851D01*
G01X568111Y261975D02*
G03X560237I-3937J0D01*
G01Y292684D02*
G03X568111I3937J0D01*
G01X560237Y551040D02*
Y292684D01*
G01X568111Y551040D02*
G03X560237I-3937J0D01*
G01X568526Y591382D02*
G03X568110Y589622I3521J-1761D01*
G01X586707Y627745D02*
X568526Y591382D01*
G01X560237Y581748D02*
G03X568111I3937J0D01*
G01X561484Y594905D02*
G03X560237Y589622I10564J-5282D01*
G01D02*
Y581748D01*
G01X579665Y631267D02*
X561484Y594904D01*
G01X524242Y763780D02*
G03X532116I3937J0D01*
G01X834646D02*
X532116D01*
G01X590228Y629921D02*
G03X586707Y627745I0J-3937D01*
G01X842520Y629921D02*
X590228D01*
G01X590229Y637796D02*
G03X579665Y631268I0J-11812D01*
G01X590229Y637796D02*
X838583D01*
G01X842520Y629921D02*
G03X846457Y633858I0J3937D01*
G01Y759843D02*
Y633858D01*
G01X838583Y637796D02*
Y709449D01*
G01X850394Y763780D02*
G03X846457Y759843I0J-3937D01*
G01X903079Y763780D02*
X850394D01*
G01X812123Y734367D02*
G03I-4292J0D01*
G01X838583Y759843D02*
G03X834646Y763780I-3937J0D01*
G01X838583Y740158D02*
G03X846457I3937J0D01*
G01Y709449D02*
G03X838583I-3937J0D01*
G01Y740158D02*
Y759843D01*
G01X921260Y0D02*
G03X925197Y3937I0J3937D01*
G01D02*
Y723480D01*
G01X906600Y761603D02*
G03X903079Y763780I-3522J-1760D01*
G01X924781Y725241D02*
X906600Y761603D01*
G01X925197Y723480D02*
G03X924781Y725241I-3937J0D01*
G54D13*
G01X353325Y122694D02*
X389951Y86068D01*
G01X352025Y122155D02*
X388651Y85529D01*
G01X353325Y156808D02*
Y122694D01*
G01X352025Y178936D02*
Y122155D01*
G01Y178936D02*
Y122155D01*
G01Y178936D02*
Y122155D01*
G01Y178936D02*
Y122155D01*
G01D02*
X388651Y85529D01*
G01X353325Y122694D02*
X389951Y86068D01*
G01X352025Y178936D02*
Y122155D01*
G01X353325Y156808D02*
Y122694D01*
G01Y161508D02*
Y159858D01*
G01Y166208D02*
Y164558D01*
G01Y179475D02*
Y169258D01*
G01X349825Y182975D02*
X353325Y179475D01*
G01X348525Y182436D02*
X352025Y178936D01*
G01X349825Y206254D02*
Y182975D01*
G01X348525Y206793D02*
Y182436D01*
G01X355225Y211654D02*
X349825Y206254D01*
G01X353325Y161508D02*
Y159858D01*
G01Y166208D02*
Y164558D01*
G01Y179475D02*
Y169258D01*
G01X348525Y182436D02*
X352025Y178936D01*
G01X349825Y182975D02*
X353325Y179475D01*
G01X348525Y206793D02*
Y182436D01*
G01X349825Y206254D02*
Y182975D01*
G01X355225Y211654D02*
X349825Y206254D01*
G01X353925Y212193D02*
X348525Y206793D01*
G01X355225Y369700D02*
Y211654D01*
G01X353925Y369161D02*
Y212193D01*
G01D02*
X348525Y206793D01*
G01X353925Y369161D02*
Y212193D01*
G01X355225Y369700D02*
Y211654D01*
G01X354625Y370300D02*
X355225Y369700D01*
G01X353325Y369761D02*
X353925Y369161D01*
G01X354625Y373769D02*
Y370300D01*
G01X353325Y374308D02*
Y369761D01*
G01X356875Y376019D02*
X354625Y373769D01*
G01X355575Y376558D02*
X353325Y374308D01*
G01X355575Y388814D02*
Y376558D01*
G01X357975Y391214D02*
X355575Y388814D01*
G01X353325Y369761D02*
X353925Y369161D01*
G01X354625Y370300D02*
X355225Y369700D01*
G01X353325Y374308D02*
Y369761D01*
G01X354625Y373769D02*
Y370300D01*
G01X355575Y376558D02*
X353325Y374308D01*
G01X356875Y376019D02*
X354625Y373769D01*
G01X355575Y388814D02*
Y376558D01*
G01X357975Y391214D02*
X355575Y388814D01*
G01X351067Y440109D02*
X359275Y431901D01*
G01X349767Y439570D02*
X357975Y431362D01*
G01X351067Y444825D02*
Y440109D01*
G01X349767Y444286D02*
Y439570D01*
G01X348926Y446966D02*
X351067Y444825D01*
G01X347626Y446427D02*
X349767Y444286D01*
G01X348926Y452752D02*
Y446966D01*
G01X347626Y452213D02*
Y446427D01*
G01X348575Y487249D02*
Y453103D01*
G01X347275Y486710D02*
Y452564D01*
G01X342725Y493099D02*
X348575Y487249D01*
G01X341425Y492560D02*
X347275Y486710D01*
G01X342725Y516387D02*
Y493099D01*
G01X341425Y516926D02*
Y492560D01*
G01X349767Y439570D02*
X357975Y431362D01*
G01X351067Y440109D02*
X359275Y431901D01*
G01X349767Y444286D02*
Y439570D01*
G01X351067Y444825D02*
Y440109D01*
G01X347626Y446427D02*
X349767Y444286D01*
G01X348926Y446966D02*
X351067Y444825D01*
G01X347626Y452213D02*
Y446427D01*
G01X348926Y452752D02*
Y446966D01*
G01X347275Y486710D02*
Y452564D01*
G01X348575Y487249D02*
Y453103D01*
G01X341425Y492560D02*
X347275Y486710D01*
G01X342725Y493099D02*
X348575Y487249D01*
G01X341425Y516926D02*
Y492560D01*
G01X342725Y516387D02*
Y493099D01*
G01X344043Y517705D02*
X342725Y516387D01*
G01X342743Y518244D02*
X341425Y516926D01*
G01X344043Y527906D02*
Y517705D01*
G01X342743Y528445D02*
Y518244D01*
G01X344475Y528338D02*
X344043Y527906D01*
G01X343175Y528877D02*
X342743Y528445D01*
G01X344475Y547343D02*
Y528338D01*
G01X343175Y546804D02*
Y528877D01*
G01X338244Y553574D02*
X344475Y547343D01*
G01X336944Y553035D02*
X343175Y546804D01*
G01X338244Y576391D02*
Y553574D01*
G01X336944Y576930D02*
Y553035D01*
G01X342743Y518244D02*
X341425Y516926D01*
G01X344043Y517705D02*
X342725Y516387D01*
G01X342743Y528445D02*
Y518244D01*
G01X344043Y527906D02*
Y517705D01*
G01X343175Y528877D02*
X342743Y528445D01*
G01X344475Y528338D02*
X344043Y527906D01*
G01X343175Y546804D02*
Y528877D01*
G01X344475Y547343D02*
Y528338D01*
G01X336944Y553035D02*
X343175Y546804D01*
G01X338244Y553574D02*
X344475Y547343D01*
G01X336944Y576930D02*
Y553035D01*
G01X338244Y576391D02*
Y553574D01*
G01X340700Y578847D02*
X338244Y576391D01*
G01X339400Y579386D02*
X336944Y576930D01*
G01X340700Y594002D02*
Y578847D01*
G01X339400Y594541D02*
Y579386D01*
G01X345600Y598902D02*
X340700Y594002D01*
G01X344300Y599441D02*
X339400Y594541D01*
G01X345600Y602629D02*
Y598902D01*
G01X344300Y602090D02*
Y599441D01*
G01X338939Y609290D02*
X345600Y602629D01*
G01X337639Y608751D02*
X344300Y602090D01*
G01X338939Y623955D02*
Y609290D01*
G01X337639Y624494D02*
Y608751D01*
G01X339784Y624800D02*
X338939Y623955D01*
G01X339245Y626100D02*
X337639Y624494D01*
G01X340637Y624800D02*
X339784D01*
G01X340624Y626100D02*
X339245D01*
G01X339400Y579386D02*
X336944Y576930D01*
G01X340700Y578847D02*
X338244Y576391D01*
G01X339400Y594541D02*
Y579386D01*
G01X340700Y594002D02*
Y578847D01*
G01X344300Y599441D02*
X339400Y594541D01*
G01X345600Y598902D02*
X340700Y594002D01*
G01X344300Y602090D02*
Y599441D01*
G01X345600Y602629D02*
Y598902D01*
G01X337639Y608751D02*
X344300Y602090D01*
G01X338939Y609290D02*
X345600Y602629D01*
G01X337639Y624494D02*
Y608751D01*
G01X338939Y623955D02*
Y609290D01*
G01X339245Y626100D02*
X337639Y624494D01*
G01X339784Y624800D02*
X338939Y623955D01*
G01X340624Y626100D02*
X339245D01*
G01X340637Y624800D02*
X339784D01*
G01X389951Y86068D02*
Y84361D01*
G01X388651Y85529D02*
Y83748D01*
G01Y85529D02*
Y83748D01*
G01X389951Y86068D02*
Y84361D01*
G01X356875Y388275D02*
Y376019D01*
G01X359275Y390675D02*
X356875Y388275D01*
G01X359275Y431901D02*
Y390675D01*
G01X357975Y431362D02*
Y391214D01*
G01X356875Y388275D02*
Y376019D01*
G01X359275Y390675D02*
X356875Y388275D01*
G01X357975Y431362D02*
Y391214D01*
G01X359275Y431901D02*
Y390675D01*
M02*
